# SCM (Grand Teton) — schematic netlist excerpt (pin names and nets, part order shuffled) for the footprints in the layout excerpt that follows; sources: Cadence DE-HDL packaged netlist, KiCad conversion of 12092022_DA0F0TMDCD0_F0T_Management_Board_D_brd_V3_OCP.brd

R858  Q_RES  4.7K 1% CHIP  pkg 0402LF  page 14 : A = P1V8_AUX ; B = FM_BOARD_BMC_REV_ID0
R377  Q_RES  10K 1% EMPTY  pkg 0402LF  page 28 : A = USB_OC0_EN ; B = GND

(kicad_pcb
	(version 20260206)
	(generator "pcbnew")
	(generator_version "10.0")
	(general
		(thickness 1.6)
		(legacy_teardrops no)
	)
	(paper "A4")
	(title_block
		(title "12092022_DA0F0TMDCD0_F0T_Management_Board_D_brd_V3_OCP.brd")
		(comment 1 "Grand Teton / footprints 386-387 of 1440")
	)
	(layers
		(0 "F.Cu" signal "TOP")
		(4 "In1.Cu" signal "GND")
		(6 "In2.Cu" signal "IN1")
		(8 "In3.Cu" signal "GND1")
		(10 "In4.Cu" signal "IN2")
		(12 "In5.Cu" signal "VCC")
		(14 "In6.Cu" signal "VCC1")
		(16 "In7.Cu" signal "IN3")
		(18 "In8.Cu" signal "GND2")
		(20 "In9.Cu" signal "IN4")
		(22 "In10.Cu" signal "GND3")
		(2 "B.Cu" signal "BOTTOM")
		(9 "F.Adhes" user "F.Adhesive")
		(11 "B.Adhes" user "B.Adhesive")
		(13 "F.Paste" user "Package Geometry/Pastemask Top")
		(15 "B.Paste" user "Package Geometry/Pastemask Bottom")
		(5 "F.SilkS" user "Ref Des/Silkscreen Top")
		(7 "B.SilkS" user "Ref Des/Silkscreen Bottom")
		(1 "F.Mask" user "Board Geometry/Soldermask Top")
		(3 "B.Mask" user "Board Geometry/Soldermask Bottom")
		(17 "Dwgs.User" user "User.Drawings")
		(19 "Cmts.User" user "User.Comments")
		(21 "Eco1.User" user "User.Eco1")
		(23 "Eco2.User" user "User.Eco2")
		(25 "Edge.Cuts" user "Board Geometry/Outline")
		(27 "Margin" user)
		(31 "F.CrtYd" user "Package Geometry/Place Bound Top")
		(29 "B.CrtYd" user "Package Geometry/Place Bound Bottom")
		(35 "F.Fab" user "Ref Des/Assembly Top")
		(33 "B.Fab" user "Ref Des/Assembly Bottom")
	)
	(footprint ""
		(layer "F.Cu")
		(at 70.358 -19.685 90)
		(property "Reference" "R858"
			(at 0 0 90)
			(layer "F.SilkS")
			(hide yes)
			(effects
				(font
					(size 1.27 1.27)
				)
			)
		)
		(property "Value" ""
			(at 0 0 90)
			(layer "F.Fab")
			(effects
				(font
					(size 1.27 1.27)
				)
			)
		)
		(duplicate_pad_numbers_are_jumpers no)
		(fp_line
			(start 0.7874 -0.4064)
			(end 0.7874 0.4064)
			(stroke
				(width 0.1524)
				(type default)
			)
			(layer "F.SilkS")
		)
		(fp_line
			(start -0.7874 -0.4064)
			(end 0.7874 -0.4064)
			(stroke
				(width 0.1524)
				(type default)
			)
			(layer "F.SilkS")
		)
		(fp_line
			(start 0.7874 0.4064)
			(end -0.7874 0.4064)
			(stroke
				(width 0.1524)
				(type default)
			)
			(layer "F.SilkS")
		)
		(fp_line
			(start -0.7874 0.4064)
			(end -0.7874 -0.4064)
			(stroke
				(width 0.1524)
				(type default)
			)
			(layer "F.SilkS")
		)
		(fp_line
			(start -0.12065 -0.305054)
			(end -0.12065 -0.2794)
			(stroke
				(width 0.1)
				(type default)
			)
			(layer "F.Fab")
		)
		(fp_line
			(start -0.67945 -0.305054)
			(end -0.12065 -0.305054)
			(stroke
				(width 0.1)
				(type default)
			)
			(layer "F.Fab")
		)
		(fp_line
			(start 0.67945 -0.3048)
			(end 0.67945 0.3048)
			(stroke
				(width 0.1)
				(type default)
			)
			(layer "F.Fab")
		)
		(fp_line
			(start 0.12065 -0.3048)
			(end 0.67945 -0.3048)
			(stroke
				(width 0.1)
				(type default)
			)
			(layer "F.Fab")
		)
		(fp_line
			(start 0.12065 -0.2794)
			(end 0.12065 -0.3048)
			(stroke
				(width 0.1)
				(type default)
			)
			(layer "F.Fab")
		)
		(fp_line
			(start -0.12065 -0.2794)
			(end 0.12065 -0.2794)
			(stroke
				(width 0.1)
				(type default)
			)
			(layer "F.Fab")
		)
		(fp_line
			(start 0.120396 0.2794)
			(end -0.12065 0.2794)
			(stroke
				(width 0.1)
				(type default)
			)
			(layer "F.Fab")
		)
		(fp_line
			(start -0.12065 0.2794)
			(end -0.12065 0.3048)
			(stroke
				(width 0.1)
				(type default)
			)
			(layer "F.Fab")
		)
		(fp_line
			(start 0.67945 0.3048)
			(end 0.120396 0.3048)
			(stroke
				(width 0.1)
				(type default)
			)
			(layer "F.Fab")
		)
		(fp_line
			(start 0.120396 0.3048)
			(end 0.120396 0.2794)
			(stroke
				(width 0.1)
				(type default)
			)
			(layer "F.Fab")
		)
		(fp_line
			(start -0.12065 0.3048)
			(end -0.67945 0.3048)
			(stroke
				(width 0.1)
				(type default)
			)
			(layer "F.Fab")
		)
		(fp_line
			(start -0.67945 0.3048)
			(end -0.67945 -0.305054)
			(stroke
				(width 0.1)
				(type default)
			)
			(layer "F.Fab")
		)
		(pad "1" smd circle
			(at -0.40005 0 90)
			(size 0 0)
			(layers "F.Cu" "F.Mask" "F.Paste")
			(net "P1V8_AUX")
		)
		(pad "2" smd circle
			(at 0.40005 0 90)
			(size 0 0)
			(layers "F.Cu" "F.Mask" "F.Paste")
			(net "FM_BOARD_BMC_REV_ID0")
		)
	)
	(footprint ""
		(layer "F.Cu")
		(at 54.84368 -24.887936)
		(property "Reference" "R377"
			(at 0 0 0)
			(layer "F.SilkS")
			(hide yes)
			(effects
				(font
					(size 1.27 1.27)
				)
			)
		)
		(property "Value" ""
			(at 0 0 0)
			(layer "F.Fab")
			(effects
				(font
					(size 1.27 1.27)
				)
			)
		)
		(duplicate_pad_numbers_are_jumpers no)
		(fp_line
			(start -0.7874 -0.4064)
			(end 0.7874 -0.4064)
			(stroke
				(width 0.1524)
				(type default)
			)
			(layer "F.SilkS")
		)
		(fp_line
			(start -0.7874 0.4064)
			(end -0.7874 -0.4064)
			(stroke
				(width 0.1524)
				(type default)
			)
			(layer "F.SilkS")
		)
		(fp_line
			(start 0.7874 -0.4064)
			(end 0.7874 0.4064)
			(stroke
				(width 0.1524)
				(type default)
			)
			(layer "F.SilkS")
		)
		(fp_line
			(start 0.7874 0.4064)
			(end -0.7874 0.4064)
			(stroke
				(width 0.1524)
				(type default)
			)
			(layer "F.SilkS")
		)
		(fp_line
			(start -0.67945 -0.305054)
			(end -0.12065 -0.305054)
			(stroke
				(width 0.1)
				(type default)
			)
			(layer "F.Fab")
		)
		(fp_line
			(start -0.67945 0.3048)
			(end -0.67945 -0.305054)
			(stroke
				(width 0.1)
				(type default)
			)
			(layer "F.Fab")
		)
		(fp_line
			(start -0.12065 -0.305054)
			(end -0.12065 -0.2794)
			(stroke
				(width 0.1)
				(type default)
			)
			(layer "F.Fab")
		)
		(fp_line
			(start -0.12065 -0.2794)
			(end 0.12065 -0.2794)
			(stroke
				(width 0.1)
				(type default)
			)
			(layer "F.Fab")
		)
		(fp_line
			(start -0.12065 0.2794)
			(end -0.12065 0.3048)
			(stroke
				(width 0.1)
				(type default)
			)
			(layer "F.Fab")
		)
		(fp_line
			(start -0.12065 0.3048)
			(end -0.67945 0.3048)
			(stroke
				(width 0.1)
				(type default)
			)
			(layer "F.Fab")
		)
		(fp_line
			(start 0.120396 0.2794)
			(end -0.12065 0.2794)
			(stroke
				(width 0.1)
				(type default)
			)
			(layer "F.Fab")
		)
		(fp_line
			(start 0.120396 0.3048)
			(end 0.120396 0.2794)
			(stroke
				(width 0.1)
				(type default)
			)
			(layer "F.Fab")
		)
		(fp_line
			(start 0.12065 -0.3048)
			(end 0.67945 -0.3048)
			(stroke
				(width 0.1)
				(type default)
			)
			(layer "F.Fab")
		)
		(fp_line
			(start 0.12065 -0.2794)
			(end 0.12065 -0.3048)
			(stroke
				(width 0.1)
				(type default)
			)
			(layer "F.Fab")
		)
		(fp_line
			(start 0.67945 -0.3048)
			(end 0.67945 0.3048)
			(stroke
				(width 0.1)
				(type default)
			)
			(layer "F.Fab")
		)
		(fp_line
			(start 0.67945 0.3048)
			(end 0.120396 0.3048)
			(stroke
				(width 0.1)
				(type default)
			)
			(layer "F.Fab")
		)
		(pad "1" smd circle
			(at -0.40005 0)
			(size 0 0)
			(layers "F.Cu" "F.Mask" "F.Paste")
			(net "USB_OC0_EN")
		)
		(pad "2" smd circle
			(at 0.40005 0)
			(size 0 0)
			(layers "F.Cu" "F.Mask" "F.Paste")
			(net "GND")
		)
	)
)
